(kicad_pcb
	(version 20260206)
	(generator "pcbnew")
	(generator_version "10.0")
	(general
		(thickness 1.6)
		(legacy_teardrops no)
	)
	(paper "A4")
	(title_block
		(title "Bryce Canyon_SCC_16316-1_OCP.brd")
		(comment 1 "Bryce Canyon / footprints 837-844 of 1561")
	)
	(layers
		(0 "F.Cu" signal "TOP")
		(4 "In1.Cu" signal "L2GND")
		(6 "In2.Cu" signal "L3")
		(8 "In3.Cu" signal "L4VCC")
		(10 "In4.Cu" signal "L5VCC")
		(12 "In5.Cu" signal "L6")
		(14 "In6.Cu" signal "L7GND")
		(2 "B.Cu" signal "BOTTOM")
		(9 "F.Adhes" user "F.Adhesive")
		(11 "B.Adhes" user "B.Adhesive")
		(13 "F.Paste" user "Package Geometry/Pastemask Top")
		(15 "B.Paste" user "Package Geometry/Pastemask Bottom")
		(5 "F.SilkS" user "Ref Des/Silkscreen Top")
		(7 "B.SilkS" user "Ref Des/Silkscreen Bottom")
		(1 "F.Mask" user "Board Geometry/Soldermask Top")
		(3 "B.Mask" user "Board Geometry/Soldermask Bottom")
		(17 "Dwgs.User" user "User.Drawings")
		(19 "Cmts.User" user "User.Comments")
		(21 "Eco1.User" user "User.Eco1")
		(23 "Eco2.User" user "User.Eco2")
		(25 "Edge.Cuts" user "Board Geometry/Outline")
		(27 "Margin" user)
		(31 "F.CrtYd" user "Package Geometry/Place Bound Top")
		(29 "B.CrtYd" user "Package Geometry/Place Bound Bottom")
		(35 "F.Fab" user "Ref Des/Assembly Top")
		(33 "B.Fab" user "Ref Des/Assembly Bottom")
	)
	(footprint ""
		(layer "B.Cu")
		(at 110.6424 -57.4802)
		(property "Reference" "C580"
			(at 0 0 0)
			(layer "B.SilkS")
			(hide yes)
			(effects
				(font
					(size 1.27 1.27)
				)
				(justify mirror)
			)
		)
		(property "Value" "SCD1U6D3V1KX-GP"
			(at 2.8321 -1.7399 0)
			(unlocked yes)
			(layer "B.Fab")
			(hide yes)
			(effects
				(font
					(size 1.016 1.016)
					(thickness 0.1524)
				)
				(justify mirror)
			)
		)
		(property "Device Type" "C0201H13"
			(at 2.8321 -3.2639 0)
			(unlocked yes)
			(layer "B.Fab")
			(hide yes)
			(effects
				(font
					(size 1.016 1.016)
					(thickness 0.1524)
				)
				(justify mirror)
			)
		)
		(duplicate_pad_numbers_are_jumpers no)
		(fp_rect
			(start 0.2794 0.6477)
			(end -0.2794 -0.6477)
			(stroke
				(width 0)
				(type default)
			)
			(fill no)
			(layer "B.CrtYd")
		)
		(fp_rect
			(start 0.2794 0.6477)
			(end -0.2794 -0.6477)
			(stroke
				(width 0)
				(type default)
			)
			(fill no)
			(layer "B.Fab")
		)
		(pad "1" smd custom
			(at 0 -0.2794 180)
			(size 0.0762 0.0762)
			(layers "B.Cu" "B.Mask" "B.Paste")
			(net "GB_VDDA")
			(options
				(clearance outline)
				(anchor circle)
			)
			(primitives
				(gr_poly
					(pts
						(arc
							(start 0.1524 0.127)
							(mid 0.137521 0.162921)
							(end 0.1016 0.1778)
						)
						(arc
							(start -0.1016 0.1778)
							(mid -0.137521 0.162921)
							(end -0.1524 0.127)
						)
						(arc
							(start -0.1524 -0.127)
							(mid -0.137521 -0.162921)
							(end -0.1016 -0.1778)
						)
						(arc
							(start 0.1016 -0.1778)
							(mid 0.137521 -0.162921)
							(end 0.1524 -0.127)
						)
					)
					(width 0)
					(fill yes)
				)
			)
		)
		(pad "2" smd custom
			(at 0 0.2794 180)
			(size 0.0762 0.0762)
			(layers "B.Cu" "B.Mask" "B.Paste")
			(net "GND")
			(options
				(clearance outline)
				(anchor circle)
			)
			(primitives
				(gr_poly
					(pts
						(arc
							(start 0.1524 0.127)
							(mid 0.137521 0.162921)
							(end 0.1016 0.1778)
						)
						(arc
							(start -0.1016 0.1778)
							(mid -0.137521 0.162921)
							(end -0.1524 0.127)
						)
						(arc
							(start -0.1524 -0.127)
							(mid -0.137521 -0.162921)
							(end -0.1016 -0.1778)
						)
						(arc
							(start 0.1016 -0.1778)
							(mid 0.137521 -0.162921)
							(end 0.1524 -0.127)
						)
					)
					(width 0)
					(fill yes)
				)
			)
		)
	)
	(footprint ""
		(layer "B.Cu")
		(at 193.25336 -19.76374 90)
		(property "Reference" "R243"
			(at 0 0 90)
			(layer "B.SilkS")
			(hide yes)
			(effects
				(font
					(size 1.27 1.27)
				)
				(justify mirror)
			)
		)
		(property "Value" "0R2J-2-GP"
			(at -0.064008 -3.993896 90)
			(unlocked yes)
			(layer "B.Fab")
			(hide yes)
			(effects
				(font
					(size 1.016 1.016)
					(thickness 0.1524)
				)
				(justify mirror)
			)
		)
		(property "Device Type" "R402H16"
			(at -0.064008 -5.517896 90)
			(unlocked yes)
			(layer "B.Fab")
			(hide yes)
			(effects
				(font
					(size 1.016 1.016)
					(thickness 0.1524)
				)
				(justify mirror)
			)
		)
		(duplicate_pad_numbers_are_jumpers no)
		(fp_line
			(start 0.508 -0.9398)
			(end 0.508 0.9398)
			(stroke
				(width 0.1524)
				(type default)
			)
			(layer "B.SilkS")
		)
		(fp_line
			(start -0.508 -0.9398)
			(end 0.508 -0.9398)
			(stroke
				(width 0.1524)
				(type default)
			)
			(layer "B.SilkS")
		)
		(fp_rect
			(start 0.508 0.9398)
			(end -0.508 -0.9398)
			(stroke
				(width 0)
				(type default)
			)
			(fill no)
			(layer "B.CrtYd")
		)
		(fp_rect
			(start 0.508 0.9398)
			(end -0.508 -0.9398)
			(stroke
				(width 0)
				(type default)
			)
			(fill no)
			(layer "B.Fab")
		)
		(pad "1" smd custom
			(at 0 -0.4445 270)
			(size 0.1397 0.1397)
			(layers "B.Cu" "B.Mask" "B.Paste")
			(net "PCIE_RST_N")
			(options
				(clearance outline)
				(anchor circle)
			)
			(primitives
				(gr_poly
					(pts
						(arc
							(start -0.1778 0.2794)
							(mid -0.249642 0.249642)
							(end -0.2794 0.1778)
						)
						(arc
							(start -0.2794 -0.1778)
							(mid -0.249642 -0.249642)
							(end -0.1778 -0.2794)
						)
						(arc
							(start 0.1778 -0.2794)
							(mid 0.249642 -0.249642)
							(end 0.2794 -0.1778)
						)
						(arc
							(start 0.2794 0.1778)
							(mid 0.249642 0.249642)
							(end 0.1778 0.2794)
						)
					)
					(width 0)
					(fill yes)
				)
			)
		)
		(pad "2" smd custom
			(at 0 0.4445 270)
			(size 0.1397 0.1397)
			(layers "B.Cu" "B.Mask" "B.Paste")
			(net "SYS_RST")
			(options
				(clearance outline)
				(anchor circle)
			)
			(primitives
				(gr_poly
					(pts
						(arc
							(start -0.1778 0.2794)
							(mid -0.249642 0.249642)
							(end -0.2794 0.1778)
						)
						(arc
							(start -0.2794 -0.1778)
							(mid -0.249642 -0.249642)
							(end -0.1778 -0.2794)
						)
						(arc
							(start 0.1778 -0.2794)
							(mid 0.249642 -0.249642)
							(end 0.2794 -0.1778)
						)
						(arc
							(start 0.2794 0.1778)
							(mid 0.249642 0.249642)
							(end 0.1778 0.2794)
						)
					)
					(width 0)
					(fill yes)
				)
			)
		)
	)
	(footprint ""
		(layer "B.Cu")
		(at 125.5776 -39.4716 180)
		(property "Reference" "C51"
			(at 0 0 0)
			(layer "B.SilkS")
			(hide yes)
			(effects
				(font
					(size 1.27 1.27)
				)
				(justify mirror)
			)
		)
		(property "Value" "SCD01U16V1KX-GP"
			(at 2.8321 -1.7399 180)
			(unlocked yes)
			(layer "B.Fab")
			(hide yes)
			(effects
				(font
					(size 1.016 1.016)
					(thickness 0.1524)
				)
				(justify mirror)
			)
		)
		(property "Device Type" "C0201H13"
			(at 2.8321 -3.2639 180)
			(unlocked yes)
			(layer "B.Fab")
			(hide yes)
			(effects
				(font
					(size 1.016 1.016)
					(thickness 0.1524)
				)
				(justify mirror)
			)
		)
		(duplicate_pad_numbers_are_jumpers no)
		(fp_rect
			(start 0.2794 0.6477)
			(end -0.2794 -0.6477)
			(stroke
				(width 0)
				(type default)
			)
			(fill no)
			(layer "B.CrtYd")
		)
		(fp_rect
			(start 0.2794 0.6477)
			(end -0.2794 -0.6477)
			(stroke
				(width 0)
				(type default)
			)
			(fill no)
			(layer "B.Fab")
		)
		(pad "1" smd custom
			(at 0 -0.2794)
			(size 0.0762 0.0762)
			(layers "B.Cu" "B.Mask" "B.Paste")
			(net "PHY_DPB_TO_SCC_38_DP")
			(options
				(clearance outline)
				(anchor circle)
			)
			(primitives
				(gr_poly
					(pts
						(arc
							(start 0.1524 0.127)
							(mid 0.137521 0.162921)
							(end 0.1016 0.1778)
						)
						(arc
							(start -0.1016 0.1778)
							(mid -0.137521 0.162921)
							(end -0.1524 0.127)
						)
						(arc
							(start -0.1524 -0.127)
							(mid -0.137521 -0.162921)
							(end -0.1016 -0.1778)
						)
						(arc
							(start 0.1016 -0.1778)
							(mid 0.137521 -0.162921)
							(end 0.1524 -0.127)
						)
					)
					(width 0)
					(fill yes)
				)
			)
		)
		(pad "2" smd custom
			(at 0 0.2794)
			(size 0.0762 0.0762)
			(layers "B.Cu" "B.Mask" "B.Paste")
			(net "PHY_DPB_TO_SCC_C_38_DP")
			(options
				(clearance outline)
				(anchor circle)
			)
			(primitives
				(gr_poly
					(pts
						(arc
							(start 0.1524 0.127)
							(mid 0.137521 0.162921)
							(end 0.1016 0.1778)
						)
						(arc
							(start -0.1016 0.1778)
							(mid -0.137521 0.162921)
							(end -0.1524 0.127)
						)
						(arc
							(start -0.1524 -0.127)
							(mid -0.137521 -0.162921)
							(end -0.1016 -0.1778)
						)
						(arc
							(start 0.1016 -0.1778)
							(mid 0.137521 -0.162921)
							(end 0.1524 -0.127)
						)
					)
					(width 0)
					(fill yes)
				)
			)
		)
	)
	(footprint ""
		(layer "B.Cu")
		(at 166.906702 -50.39741)
		(property "Reference" "TP126"
			(at 0 0 0)
			(layer "B.SilkS")
			(hide yes)
			(effects
				(font
					(size 1.27 1.27)
				)
				(justify mirror)
			)
		)
		(property "Value" "TPAD28-2-GP"
			(at 0.0127 -1.6637 0)
			(unlocked yes)
			(layer "B.Fab")
			(hide yes)
			(effects
				(font
					(size 1.016 1.016)
					(thickness 0.1524)
				)
				(justify mirror)
			)
		)
		(property "Device Type" "TPAD28"
			(at 0.0127 -3.1877 0)
			(unlocked yes)
			(layer "B.Fab")
			(hide yes)
			(effects
				(font
					(size 1.016 1.016)
					(thickness 0.1524)
				)
				(justify mirror)
			)
		)
		(duplicate_pad_numbers_are_jumpers no)
		(fp_poly
			(pts
				(arc
					(start 0.3556 0)
					(mid -0.3556 0)
					(end 0.3556 0)
				)
			)
			(stroke
				(width 0)
				(type default)
			)
			(fill no)
			(layer "B.CrtYd")
		)
		(fp_poly
			(pts
				(arc
					(start 0.6096 0)
					(mid -0.6096 0)
					(end 0.6096 0)
				)
			)
			(stroke
				(width 0)
				(type default)
			)
			(fill no)
			(layer "B.Fab")
		)
		(pad "1" smd circle
			(at 0 0 180)
			(size 0.7112 0.7112)
			(layers "B.Cu" "B.Mask" "B.Paste")
			(net "ICE1_TDI")
		)
	)
	(footprint ""
		(layer "B.Cu")
		(at 170.721274 -97.760282)
		(property "Reference" "R496"
			(at 0 0 0)
			(layer "B.SilkS")
			(hide yes)
			(effects
				(font
					(size 1.27 1.27)
				)
				(justify mirror)
			)
		)
		(property "Value" "100KR2F-L1-GP"
			(at -0.064008 -3.993896 0)
			(unlocked yes)
			(layer "B.Fab")
			(hide yes)
			(effects
				(font
					(size 1.016 1.016)
					(thickness 0.1524)
				)
				(justify mirror)
			)
		)
		(property "Device Type" "R402H16"
			(at -0.064008 -5.517896 0)
			(unlocked yes)
			(layer "B.Fab")
			(hide yes)
			(effects
				(font
					(size 1.016 1.016)
					(thickness 0.1524)
				)
				(justify mirror)
			)
		)
		(duplicate_pad_numbers_are_jumpers no)
		(fp_line
			(start -0.508 -0.9398)
			(end 0.508 -0.9398)
			(stroke
				(width 0.1524)
				(type default)
			)
			(layer "B.SilkS")
		)
		(fp_line
			(start 0.508 -0.9398)
			(end 0.508 0.9398)
			(stroke
				(width 0.1524)
				(type default)
			)
			(layer "B.SilkS")
		)
		(fp_rect
			(start 0.508 0.9398)
			(end -0.508 -0.9398)
			(stroke
				(width 0)
				(type default)
			)
			(fill no)
			(layer "B.CrtYd")
		)
		(fp_rect
			(start 0.508 0.9398)
			(end -0.508 -0.9398)
			(stroke
				(width 0)
				(type default)
			)
			(fill no)
			(layer "B.Fab")
		)
		(pad "1" smd custom
			(at 0 -0.4445 180)
			(size 0.1397 0.1397)
			(layers "B.Cu" "B.Mask" "B.Paste")
			(net "VT235_VDES")
			(options
				(clearance outline)
				(anchor circle)
			)
			(primitives
				(gr_poly
					(pts
						(arc
							(start -0.1778 0.2794)
							(mid -0.249642 0.249642)
							(end -0.2794 0.1778)
						)
						(arc
							(start -0.2794 -0.1778)
							(mid -0.249642 -0.249642)
							(end -0.1778 -0.2794)
						)
						(arc
							(start 0.1778 -0.2794)
							(mid 0.249642 -0.249642)
							(end 0.2794 -0.1778)
						)
						(arc
							(start 0.2794 0.1778)
							(mid 0.249642 0.249642)
							(end 0.1778 0.2794)
						)
					)
					(width 0)
					(fill yes)
				)
			)
		)
		(pad "2" smd custom
			(at 0 0.4445 180)
			(size 0.1397 0.1397)
			(layers "B.Cu" "B.Mask" "B.Paste")
			(net "AVSO_VREF")
			(options
				(clearance outline)
				(anchor circle)
			)
			(primitives
				(gr_poly
					(pts
						(arc
							(start -0.1778 0.2794)
							(mid -0.249642 0.249642)
							(end -0.2794 0.1778)
						)
						(arc
							(start -0.2794 -0.1778)
							(mid -0.249642 -0.249642)
							(end -0.1778 -0.2794)
						)
						(arc
							(start 0.1778 -0.2794)
							(mid 0.249642 -0.249642)
							(end 0.2794 -0.1778)
						)
						(arc
							(start 0.2794 0.1778)
							(mid 0.249642 0.249642)
							(end 0.1778 0.2794)
						)
					)
					(width 0)
					(fill yes)
				)
			)
		)
	)
	(footprint ""
		(layer "B.Cu")
		(at 109.2962 -72.009)
		(property "Reference" "C148"
			(at 0 0 0)
			(layer "B.SilkS")
			(hide yes)
			(effects
				(font
					(size 1.27 1.27)
				)
				(justify mirror)
			)
		)
		(property "Value" "SCD1U6D3V1KX-GP"
			(at 2.8321 -1.7399 0)
			(unlocked yes)
			(layer "B.Fab")
			(hide yes)
			(effects
				(font
					(size 1.016 1.016)
					(thickness 0.1524)
				)
				(justify mirror)
			)
		)
		(property "Device Type" "C0201H13"
			(at 2.8321 -3.2639 0)
			(unlocked yes)
			(layer "B.Fab")
			(hide yes)
			(effects
				(font
					(size 1.016 1.016)
					(thickness 0.1524)
				)
				(justify mirror)
			)
		)
		(duplicate_pad_numbers_are_jumpers no)
		(fp_rect
			(start 0.2794 0.6477)
			(end -0.2794 -0.6477)
			(stroke
				(width 0)
				(type default)
			)
			(fill no)
			(layer "B.CrtYd")
		)
		(fp_rect
			(start 0.2794 0.6477)
			(end -0.2794 -0.6477)
			(stroke
				(width 0)
				(type default)
			)
			(fill no)
			(layer "B.Fab")
		)
		(pad "1" smd custom
			(at 0 -0.2794 180)
			(size 0.0762 0.0762)
			(layers "B.Cu" "B.Mask" "B.Paste")
			(net "P1V8_E")
			(options
				(clearance outline)
				(anchor circle)
			)
			(primitives
				(gr_poly
					(pts
						(arc
							(start 0.1524 0.127)
							(mid 0.137521 0.162921)
							(end 0.1016 0.1778)
						)
						(arc
							(start -0.1016 0.1778)
							(mid -0.137521 0.162921)
							(end -0.1524 0.127)
						)
						(arc
							(start -0.1524 -0.127)
							(mid -0.137521 -0.162921)
							(end -0.1016 -0.1778)
						)
						(arc
							(start 0.1016 -0.1778)
							(mid 0.137521 -0.162921)
							(end 0.1524 -0.127)
						)
					)
					(width 0)
					(fill yes)
				)
			)
		)
		(pad "2" smd custom
			(at 0 0.2794 180)
			(size 0.0762 0.0762)
			(layers "B.Cu" "B.Mask" "B.Paste")
			(net "GND")
			(options
				(clearance outline)
				(anchor circle)
			)
			(primitives
				(gr_poly
					(pts
						(arc
							(start 0.1524 0.127)
							(mid 0.137521 0.162921)
							(end 0.1016 0.1778)
						)
						(arc
							(start -0.1016 0.1778)
							(mid -0.137521 0.162921)
							(end -0.1524 0.127)
						)
						(arc
							(start -0.1524 -0.127)
							(mid -0.137521 -0.162921)
							(end -0.1016 -0.1778)
						)
						(arc
							(start 0.1016 -0.1778)
							(mid 0.137521 -0.162921)
							(end 0.1524 -0.127)
						)
					)
					(width 0)
					(fill yes)
				)
			)
		)
	)
	(footprint ""
		(layer "B.Cu")
		(at 163.302442 -36.807394 90)
		(property "Reference" "C376"
			(at 0 0 90)
			(layer "B.SilkS")
			(hide yes)
			(effects
				(font
					(size 1.27 1.27)
				)
				(justify mirror)
			)
		)
		(property "Value" "SCD1U16V2KX-3GP"
			(at -1.1811 -2.7051 90)
			(unlocked yes)
			(layer "B.Fab")
			(hide yes)
			(effects
				(font
					(size 1.016 1.016)
					(thickness 0.1524)
				)
				(justify mirror)
			)
		)
		(property "Device Type" "C402H22"
			(at -1.1811 -4.2291 90)
			(unlocked yes)
			(layer "B.Fab")
			(hide yes)
			(effects
				(font
					(size 1.016 1.016)
					(thickness 0.1524)
				)
				(justify mirror)
			)
		)
		(duplicate_pad_numbers_are_jumpers no)
		(fp_rect
			(start 0.4318 0.9525)
			(end -0.4318 -0.9525)
			(stroke
				(width 0)
				(type default)
			)
			(fill no)
			(layer "B.CrtYd")
		)
		(fp_rect
			(start 0.4318 0.9525)
			(end -0.4318 -0.9525)
			(stroke
				(width 0)
				(type default)
			)
			(fill no)
			(layer "B.Fab")
		)
		(pad "1" smd custom
			(at 0 -0.4445 270)
			(size 0.1524 0.1524)
			(layers "B.Cu" "B.Mask" "B.Paste")
			(net "SAS0_VDDH")
			(options
				(clearance outline)
				(anchor circle)
			)
			(primitives
				(gr_poly
					(pts
						(arc
							(start 0.3048 0.2032)
							(mid 0.275042 0.275042)
							(end 0.2032 0.3048)
						)
						(arc
							(start -0.2032 0.3048)
							(mid -0.275042 0.275042)
							(end -0.3048 0.2032)
						)
						(arc
							(start -0.3048 -0.2032)
							(mid -0.275042 -0.275042)
							(end -0.2032 -0.3048)
						)
						(arc
							(start 0.2032 -0.3048)
							(mid 0.275042 -0.275042)
							(end 0.3048 -0.2032)
						)
					)
					(width 0)
					(fill yes)
				)
			)
		)
		(pad "2" smd custom
			(at 0 0.4445 270)
			(size 0.1524 0.1524)
			(layers "B.Cu" "B.Mask" "B.Paste")
			(net "GND")
			(options
				(clearance outline)
				(anchor circle)
			)
			(primitives
				(gr_poly
					(pts
						(arc
							(start 0.3048 0.2032)
							(mid 0.275042 0.275042)
							(end 0.2032 0.3048)
						)
						(arc
							(start -0.2032 0.3048)
							(mid -0.275042 0.275042)
							(end -0.3048 0.2032)
						)
						(arc
							(start -0.3048 -0.2032)
							(mid -0.275042 -0.275042)
							(end -0.2032 -0.3048)
						)
						(arc
							(start 0.2032 -0.3048)
							(mid 0.275042 -0.275042)
							(end 0.3048 -0.2032)
						)
					)
					(width 0)
					(fill yes)
				)
			)
		)
	)
	(footprint ""
		(layer "B.Cu")
		(at 174.216568 -48.194722 -90)
		(property "Reference" "C460"
			(at 0 0 90)
			(layer "B.SilkS")
			(hide yes)
			(effects
				(font
					(size 1.27 1.27)
				)
				(justify mirror)
			)
		)
		(property "Value" "SCD1U6D3V1KX-GP"
			(at 2.8321 -1.7399 270)
			(unlocked yes)
			(layer "B.Fab")
			(hide yes)
			(effects
				(font
					(size 1.016 1.016)
					(thickness 0.1524)
				)
				(justify mirror)
			)
		)
		(property "Device Type" "C0201H13"
			(at 2.8321 -3.2639 270)
			(unlocked yes)
			(layer "B.Fab")
			(hide yes)
			(effects
				(font
					(size 1.016 1.016)
					(thickness 0.1524)
				)
				(justify mirror)
			)
		)
		(duplicate_pad_numbers_are_jumpers no)
		(fp_rect
			(start 0.2794 0.6477)
			(end -0.2794 -0.6477)
			(stroke
				(width 0)
				(type default)
			)
			(fill no)
			(layer "B.CrtYd")
		)
		(fp_rect
			(start 0.2794 0.6477)
			(end -0.2794 -0.6477)
			(stroke
				(width 0)
				(type default)
			)
			(fill no)
			(layer "B.Fab")
		)
		(pad "1" smd custom
			(at 0 -0.2794 90)
			(size 0.0762 0.0762)
			(layers "B.Cu" "B.Mask" "B.Paste")
			(net "P1V8_C")
			(options
				(clearance outline)
				(anchor circle)
			)
			(primitives
				(gr_poly
					(pts
						(arc
							(start 0.1524 0.127)
							(mid 0.137521 0.162921)
							(end 0.1016 0.1778)
						)
						(arc
							(start -0.1016 0.1778)
							(mid -0.137521 0.162921)
							(end -0.1524 0.127)
						)
						(arc
							(start -0.1524 -0.127)
							(mid -0.137521 -0.162921)
							(end -0.1016 -0.1778)
						)
						(arc
							(start 0.1016 -0.1778)
							(mid 0.137521 -0.162921)
							(end 0.1524 -0.127)
						)
					)
					(width 0)
					(fill yes)
				)
			)
		)
		(pad "2" smd custom
			(at 0 0.2794 90)
			(size 0.0762 0.0762)
			(layers "B.Cu" "B.Mask" "B.Paste")
			(net "GND")
			(options
				(clearance outline)
				(anchor circle)
			)
			(primitives
				(gr_poly
					(pts
						(arc
							(start 0.1524 0.127)
							(mid 0.137521 0.162921)
							(end 0.1016 0.1778)
						)
						(arc
							(start -0.1016 0.1778)
							(mid -0.137521 0.162921)
							(end -0.1524 0.127)
						)
						(arc
							(start -0.1524 -0.127)
							(mid -0.137521 -0.162921)
							(end -0.1016 -0.1778)
						)
						(arc
							(start 0.1016 -0.1778)
							(mid 0.137521 -0.162921)
							(end 0.1524 -0.127)
						)
					)
					(width 0)
					(fill yes)
				)
			)
		)
	)
)
